(kicad_pcb
	(version 20260206)
	(generator "pcbnew")
	(generator_version "10.0")
	(general
		(thickness 1.6)
		(legacy_teardrops no)
	)
	(paper "A4")
	(title_block
		(title "Bryce Canyon_F.DPB_16315-1-OCP.brd")
		(comment 1 "Bryce Canyon / footprints 406-406 of 2223")
	)
	(layers
		(0 "F.Cu" signal "TOP")
		(4 "In1.Cu" signal "L2GND")
		(6 "In2.Cu" signal "L3")
		(8 "In3.Cu" signal "L4GND")
		(10 "In4.Cu" signal "L5")
		(12 "In5.Cu" signal "L6VCC")
		(14 "In6.Cu" signal "L7VCC")
		(16 "In7.Cu" signal "L8")
		(18 "In8.Cu" signal "L9GND")
		(20 "In9.Cu" signal "L10")
		(22 "In10.Cu" signal "L11GND")
		(2 "B.Cu" signal "BOTTOM")
		(9 "F.Adhes" user "F.Adhesive")
		(11 "B.Adhes" user "B.Adhesive")
		(13 "F.Paste" user "Package Geometry/Pastemask Top")
		(15 "B.Paste" user "Package Geometry/Pastemask Bottom")
		(5 "F.SilkS" user "Ref Des/Silkscreen Top")
		(7 "B.SilkS" user "Ref Des/Silkscreen Bottom")
		(1 "F.Mask" user "Board Geometry/Soldermask Top")
		(3 "B.Mask" user "Board Geometry/Soldermask Bottom")
		(17 "Dwgs.User" user "User.Drawings")
		(19 "Cmts.User" user "User.Comments")
		(21 "Eco1.User" user "User.Eco1")
		(23 "Eco2.User" user "User.Eco2")
		(25 "Edge.Cuts" user "Board Geometry/Outline")
		(27 "Margin" user)
		(31 "F.CrtYd" user "Package Geometry/Place Bound Top")
		(29 "B.CrtYd" user "Package Geometry/Place Bound Bottom")
		(35 "F.Fab" user "Ref Des/Assembly Top")
		(33 "B.Fab" user "Ref Des/Assembly Bottom")
	)
	(footprint ""
		(layer "F.Cu")
		(at 133.89483 -142.61338)
		(property "Reference" "Q6"
			(at 0 0 0)
			(layer "F.SilkS")
			(hide yes)
			(effects
				(font
					(size 1.27 1.27)
				)
			)
		)
		(property "Value" "MMBT3904TT1G-GP"
			(at 0 -9.7282 0)
			(unlocked yes)
			(layer "F.Fab")
			(hide yes)
			(effects
				(font
					(size 1.016 1.016)
					(thickness 0.1524)
				)
			)
		)
		(property "Device Type" "SC75CBE1D6H36"
			(at 0 -11.6332 0)
			(unlocked yes)
			(layer "F.Fab")
			(hide yes)
			(effects
				(font
					(size 1.016 1.016)
					(thickness 0.1524)
				)
			)
		)
		(duplicate_pad_numbers_are_jumpers no)
		(fp_line
			(start -0.9652 -1.3716)
			(end -0.9652 1.3716)
			(stroke
				(width 0.1524)
				(type default)
			)
			(layer "F.SilkS")
		)
		(fp_line
			(start -0.9652 1.3716)
			(end 0.9652 1.3716)
			(stroke
				(width 0.1524)
				(type default)
			)
			(layer "F.SilkS")
		)
		(fp_line
			(start 0.9652 -1.3716)
			(end -0.9652 -1.3716)
			(stroke
				(width 0.1524)
				(type default)
			)
			(layer "F.SilkS")
		)
		(fp_line
			(start 0.9652 1.3716)
			(end 0.9652 -1.3716)
			(stroke
				(width 0.1524)
				(type default)
			)
			(layer "F.SilkS")
		)
		(fp_rect
			(start -1.0414 1.4478)
			(end 1.0414 -1.4478)
			(stroke
				(width 0)
				(type default)
			)
			(fill no)
			(layer "F.CrtYd")
		)
		(fp_poly
			(pts
				(xy -1.0414 -1.4478) (xy 1.0414 -1.4478) (xy 1.0414 1.4478) (xy -1.0414 1.4478)
			)
			(stroke
				(width 0)
				(type default)
			)
			(fill no)
			(layer "F.Fab")
		)
		(pad "B" smd custom
			(at -0.508 0.7112)
			(size 0.127 0.127)
			(layers "F.Cu" "F.Mask" "F.Paste")
			(net "VCCP_A")
			(options
				(clearance outline)
				(anchor circle)
			)
			(primitives
				(gr_poly
					(pts
						(arc
							(start -0.044958 0.4572)
							(mid -0.192463 0.399794)
							(end -0.254 0.254)
						)
						(xy -0.254 -0.254)
						(arc
							(start -0.253746 -0.254)
							(mid -0.192968 -0.398936)
							(end -0.04699 -0.4572)
						)
						(arc
							(start 0.04699 -0.4572)
							(mid 0.192989 -0.398958)
							(end 0.253746 -0.254)
						)
						(xy 0.254 -0.254)
						(arc
							(start 0.254 0.254)
							(mid 0.192404 0.399734)
							(end 0.044958 0.4572)
						)
					)
					(width 0)
					(fill yes)
				)
			)
		)
		(pad "C" smd custom
			(at 0 -0.7112)
			(size 0.127 0.127)
			(layers "F.Cu" "F.Mask" "F.Paste")
			(net "P12V_A")
			(options
				(clearance outline)
				(anchor circle)
			)
			(primitives
				(gr_poly
					(pts
						(arc
							(start -0.044958 0.4572)
							(mid -0.192463 0.399794)
							(end -0.254 0.254)
						)
						(xy -0.254 -0.254)
						(arc
							(start -0.253746 -0.254)
							(mid -0.192968 -0.398936)
							(end -0.04699 -0.4572)
						)
						(arc
							(start 0.04699 -0.4572)
							(mid 0.192989 -0.398958)
							(end 0.253746 -0.254)
						)
						(xy 0.254 -0.254)
						(arc
							(start 0.254 0.254)
							(mid 0.192404 0.399734)
							(end 0.044958 0.4572)
						)
					)
					(width 0)
					(fill yes)
				)
			)
		)
		(pad "E" smd custom
			(at 0.508 0.7112)
			(size 0.127 0.127)
			(layers "F.Cu" "F.Mask" "F.Paste")
			(net "P3V3_A_BIAS")
			(options
				(clearance outline)
				(anchor circle)
			)
			(primitives
				(gr_poly
					(pts
						(arc
							(start -0.044958 0.4572)
							(mid -0.192463 0.399794)
							(end -0.254 0.254)
						)
						(xy -0.254 -0.254)
						(arc
							(start -0.253746 -0.254)
							(mid -0.192968 -0.398936)
							(end -0.04699 -0.4572)
						)
						(arc
							(start 0.04699 -0.4572)
							(mid 0.192989 -0.398958)
							(end 0.253746 -0.254)
						)
						(xy 0.254 -0.254)
						(arc
							(start 0.254 0.254)
							(mid 0.192404 0.399734)
							(end 0.044958 0.4572)
						)
					)
					(width 0)
					(fill yes)
				)
			)
		)
	)
)
